FILE_TYPE = MULTI_PHYS_TABLE;
PART 'PNP'
{========================================================================================}
:VALUE       | PACK_TYPE | MATERIAL |PART_NUMBER      = EnvComp                  | PART_NUMBER | JEDEC_TYPE    | CLASS | DESCRIPTION                        | HEIGHT     | COMPONENT_TYPE | LEAD_LENGTH | LPID   | SPEED_URL | Status |RPL| AML | Bus_Unit | Days ;
{========================================================================================}
'MPS2907'    | 'TO92'    | 'IC'     | 'G73554-001'(!) = 'YES;YES;CNC;CNC;ok;VLD' | 'G73554-001' | 'TO92SB'     |'IC'   | 'IC,THM,PNP XSTR,SO-92,2907'       | '0.367 IN' | 'THMT'         | '0.343'     |''      | 'http://speed.intel.com:8081/speed/module/pdm/item/pdm_item_detail_direct.asp?item_cde=G73554-001&item_rev=01&url_param=unused' | 'Design' | 'NO' | '1' | 'SMO_IC' | '???' 
'MPS2907'    | 'TO92'    | 'EMPTY'  | 'G73554-001'(!) = 'YES;YES;CNC;CNC;ok;VLD' | 'G73554-001' | 'TO92SB'     |'IO'   | 'IC,THM,PNP XSTR,SO-92,2907'       | '0.367 IN' | 'THMT'         | '0.343'     |''      | 'http://speed.intel.com:8081/speed/module/pdm/item/pdm_item_detail_direct.asp?item_cde=G73554-001&item_rev=01&url_param=unused' | 'Design' | 'NO' | '1' | 'SMO_IC' | '???' 
'MPS2907'    | 'TO92P'   | 'IC'     | 'G73554-001'(!) = 'YES;YES;CNC;CNC;ok;VLD' | 'G73554-001' | 'TO92SB_PIP' |'IC'   | 'IC,THM,PNP XSTR,SO-92,2907'       | '0.367 IN' | 'THMT'         | '0.343'     | ''     | 'http://speed.intel.com:8081/speed/module/pdm/item/pdm_item_detail_direct.asp?item_cde=G73554-001&item_rev=01&url_param=unused' | 'Design' | 'NO' | '1' | 'SMO_IC' | '???' 
'MPS2907'    | 'TO92P'   | 'EMPTY'  | 'G73554-001'(!) = 'YES;YES;CNC;CNC;ok;VLD' | 'G73554-001' | 'TO92SB_PIP' |'IO'   | 'IC,THM,PNP XSTR,SO-92,2907'       | '0.367 IN' | 'THMT'         | '0.343'     | ''     | 'http://speed.intel.com:8081/speed/module/pdm/item/pdm_item_detail_direct.asp?item_cde=G73554-001&item_rev=01&url_param=unused' | 'Design' | 'NO' | '1' | 'SMO_IC' | '???' 
END_PART																							        
END.																								        
